(kicad_pcb
	(version 20260206)
	(generator "pcbnew")
	(generator_version "10.0")
	(general
		(thickness 1.6)
		(legacy_teardrops no)
	)
	(paper "A4")
	(title_block
		(title "Wiwynn_Tioga_Pass_MB.brd")
		(comment 1 "Tioga Pass / footprints 1325-1333 of 4770")
	)
	(layers
		(0 "F.Cu" signal "TOP")
		(4 "In1.Cu" signal "L2GND")
		(6 "In2.Cu" signal "L3")
		(8 "In3.Cu" signal "L4GND")
		(10 "In4.Cu" signal "L5")
		(12 "In5.Cu" signal "L6GND")
		(14 "In6.Cu" signal "L7VCC")
		(16 "In7.Cu" signal "L8VCC")
		(18 "In8.Cu" signal "L9GND")
		(20 "In9.Cu" signal "L10")
		(22 "In10.Cu" signal "L11GND")
		(24 "In11.Cu" signal "L12")
		(26 "In12.Cu" signal "L13GND")
		(2 "B.Cu" signal "BOTTOM")
		(9 "F.Adhes" user "F.Adhesive")
		(11 "B.Adhes" user "B.Adhesive")
		(13 "F.Paste" user "Package Geometry/Pastemask Top")
		(15 "B.Paste" user "Package Geometry/Pastemask Bottom")
		(5 "F.SilkS" user "Ref Des/Silkscreen Top")
		(7 "B.SilkS" user "Ref Des/Silkscreen Bottom")
		(1 "F.Mask" user "Board Geometry/Soldermask Top")
		(3 "B.Mask" user "Board Geometry/Soldermask Bottom")
		(17 "Dwgs.User" user "User.Drawings")
		(19 "Cmts.User" user "User.Comments")
		(21 "Eco1.User" user "User.Eco1")
		(23 "Eco2.User" user "User.Eco2")
		(25 "Edge.Cuts" user "Board Geometry/Outline")
		(27 "Margin" user)
		(31 "F.CrtYd" user "Package Geometry/Place Bound Top")
		(29 "B.CrtYd" user "Package Geometry/Place Bound Bottom")
		(35 "F.Fab" user "Ref Des/Assembly Top")
		(33 "B.Fab" user "Ref Des/Assembly Bottom")
	)
	(footprint ""
		(layer "F.Cu")
		(at 8.616188 -142.883128 -90)
		(property "Reference" "CT11"
			(at -0.8382 -0.67818 270)
			(unlocked yes)
			(layer "F.SilkS")
			(effects
				(font
					(size 0.4064 0.254)
					(thickness 0.1524)
				)
				(justify left)
			)
		)
		(property "Value" ""
			(at 0 0 270)
			(layer "F.Fab")
			(effects
				(font
					(size 1.27 1.27)
				)
			)
		)
		(duplicate_pad_numbers_are_jumpers no)
		(fp_poly
			(pts
				(xy 0.3048 -0.1016) (xy 0.3048 0.9906) (xy -0.3048 0.9906) (xy -0.3048 -0.1016)
			)
			(stroke
				(width 0)
				(type default)
			)
			(fill no)
			(layer "F.CrtYd")
		)
		(fp_line
			(start -0.3048 0.9906)
			(end 0.3048 0.9906)
			(stroke
				(width 0.1)
				(type default)
			)
			(layer "F.Fab")
		)
		(fp_line
			(start 0.3048 0.9906)
			(end 0.3048 -0.1016)
			(stroke
				(width 0.1)
				(type default)
			)
			(layer "F.Fab")
		)
		(fp_line
			(start -0.3048 -0.1016)
			(end -0.3048 0.9906)
			(stroke
				(width 0.1)
				(type default)
			)
			(layer "F.Fab")
		)
		(fp_line
			(start 0.3048 -0.1016)
			(end -0.3048 -0.1016)
			(stroke
				(width 0.1)
				(type default)
			)
			(layer "F.Fab")
		)
		(pad "1" smd rect
			(at 0 0 270)
			(size 0.508 0.508)
			(layers "F.Cu" "F.Mask" "F.Paste")
			(net "VR_PVDDQ_KLM_PH2_SW")
		)
		(pad "2" smd rect
			(at 0 0.889 270)
			(size 0.508 0.508)
			(layers "F.Cu" "F.Mask" "F.Paste")
			(net "VR_PVDDQ_KLM_PH2_RC")
		)
		(zone
			(layer "F.Cu")
			(hatch none 0.5)
			(connect_pads
				(clearance 0)
			)
			(min_thickness 0.25)
			(keepout
				(tracks not_allowed)
				(vias allowed)
				(pads allowed)
				(copperpour not_allowed)
				(footprints allowed)
			)
			(placement
				(enabled no)
				(sheetname "")
			)
			(fill
				(thermal_gap 0.5)
				(thermal_bridge_width 0.5)
				(island_removal_mode 0)
			)
			(polygon
				(pts
					(xy 7.981188 -143.137128) (xy 7.981188 -142.629128) (xy 8.362188 -142.629128) (xy 8.362188 -143.137128)
				)
			)
		)
		(zone
			(layer "F.Cu")
			(hatch none 0.5)
			(connect_pads
				(clearance 0)
			)
			(min_thickness 0.25)
			(keepout
				(tracks allowed)
				(vias not_allowed)
				(pads allowed)
				(copperpour not_allowed)
				(footprints allowed)
			)
			(placement
				(enabled no)
				(sheetname "")
			)
			(fill
				(thermal_gap 0.5)
				(thermal_bridge_width 0.5)
				(island_removal_mode 0)
			)
			(polygon
				(pts
					(xy 8.362188 -143.137128) (xy 8.362188 -142.629128) (xy 7.981188 -142.629128) (xy 7.981188 -143.137128)
				)
			)
		)
	)
	(footprint ""
		(layer "F.Cu")
		(at 408.923236 -47.825914 180)
		(property "Reference" "R1T10"
			(at 0 0 180)
			(layer "F.SilkS")
			(hide yes)
			(effects
				(font
					(size 1.27 1.27)
				)
			)
		)
		(property "Value" ""
			(at 0 0 180)
			(layer "F.Fab")
			(effects
				(font
					(size 1.27 1.27)
				)
			)
		)
		(duplicate_pad_numbers_are_jumpers no)
		(fp_poly
			(pts
				(xy -0.2794 -0.1016) (xy 0.2794 -0.1016) (xy 0.2794 0.9906) (xy -0.2794 0.9906)
			)
			(stroke
				(width 0)
				(type default)
			)
			(fill no)
			(layer "F.CrtYd")
		)
		(fp_line
			(start 0.2794 0.9906)
			(end 0.2794 -0.1016)
			(stroke
				(width 0.1)
				(type default)
			)
			(layer "F.Fab")
		)
		(fp_line
			(start 0.2794 -0.1016)
			(end -0.2794 -0.1016)
			(stroke
				(width 0.1)
				(type default)
			)
			(layer "F.Fab")
		)
		(fp_line
			(start -0.2794 0.9906)
			(end 0.2794 0.9906)
			(stroke
				(width 0.1)
				(type default)
			)
			(layer "F.Fab")
		)
		(fp_line
			(start -0.2794 -0.1016)
			(end -0.2794 0.9906)
			(stroke
				(width 0.1)
				(type default)
			)
			(layer "F.Fab")
		)
		(pad "1" smd rect
			(at 0 0 180)
			(size 0.508 0.508)
			(layers "F.Cu" "F.Mask" "F.Paste")
			(net "FM_BOARD_REV_ID0")
		)
		(pad "2" smd rect
			(at 0 0.889 180)
			(size 0.508 0.508)
			(layers "F.Cu" "F.Mask" "F.Paste")
			(net "GND")
		)
	)
	(footprint ""
		(layer "F.Cu")
		(at 39.8018 -69.3166 -90)
		(property "Reference" "CT18"
			(at -0.8382 -0.67818 270)
			(unlocked yes)
			(layer "F.SilkS")
			(effects
				(font
					(size 0.4064 0.254)
					(thickness 0.1524)
				)
				(justify left)
			)
		)
		(property "Value" ""
			(at 0 0 270)
			(layer "F.Fab")
			(effects
				(font
					(size 1.27 1.27)
				)
			)
		)
		(duplicate_pad_numbers_are_jumpers no)
		(fp_poly
			(pts
				(xy 0.3048 -0.1016) (xy 0.3048 0.9906) (xy -0.3048 0.9906) (xy -0.3048 -0.1016)
			)
			(stroke
				(width 0)
				(type default)
			)
			(fill no)
			(layer "F.CrtYd")
		)
		(fp_line
			(start -0.3048 0.9906)
			(end 0.3048 0.9906)
			(stroke
				(width 0.1)
				(type default)
			)
			(layer "F.Fab")
		)
		(fp_line
			(start 0.3048 0.9906)
			(end 0.3048 -0.1016)
			(stroke
				(width 0.1)
				(type default)
			)
			(layer "F.Fab")
		)
		(fp_line
			(start -0.3048 -0.1016)
			(end -0.3048 0.9906)
			(stroke
				(width 0.1)
				(type default)
			)
			(layer "F.Fab")
		)
		(fp_line
			(start 0.3048 -0.1016)
			(end -0.3048 -0.1016)
			(stroke
				(width 0.1)
				(type default)
			)
			(layer "F.Fab")
		)
		(pad "1" smd rect
			(at 0 0 270)
			(size 0.508 0.508)
			(layers "F.Cu" "F.Mask" "F.Paste")
			(net "VR_PVCCIN_CPU1_PHASE3")
		)
		(pad "2" smd rect
			(at 0 0.889 270)
			(size 0.508 0.508)
			(layers "F.Cu" "F.Mask" "F.Paste")
			(net "VR_PVCCIN_CPU1_PHASE3_RC")
		)
		(zone
			(layer "F.Cu")
			(hatch none 0.5)
			(connect_pads
				(clearance 0)
			)
			(min_thickness 0.25)
			(keepout
				(tracks not_allowed)
				(vias allowed)
				(pads allowed)
				(copperpour not_allowed)
				(footprints allowed)
			)
			(placement
				(enabled no)
				(sheetname "")
			)
			(fill
				(thermal_gap 0.5)
				(thermal_bridge_width 0.5)
				(island_removal_mode 0)
			)
			(polygon
				(pts
					(xy 39.1668 -69.5706) (xy 39.1668 -69.0626) (xy 39.5478 -69.0626) (xy 39.5478 -69.5706)
				)
			)
		)
		(zone
			(layer "F.Cu")
			(hatch none 0.5)
			(connect_pads
				(clearance 0)
			)
			(min_thickness 0.25)
			(keepout
				(tracks allowed)
				(vias not_allowed)
				(pads allowed)
				(copperpour not_allowed)
				(footprints allowed)
			)
			(placement
				(enabled no)
				(sheetname "")
			)
			(fill
				(thermal_gap 0.5)
				(thermal_bridge_width 0.5)
				(island_removal_mode 0)
			)
			(polygon
				(pts
					(xy 39.5478 -69.5706) (xy 39.5478 -69.0626) (xy 39.1668 -69.0626) (xy 39.1668 -69.5706)
				)
			)
		)
	)
	(footprint ""
		(layer "F.Cu")
		(at 165.354 -74.803)
		(property "Reference" "C4D24"
			(at 0 0 0)
			(layer "F.SilkS")
			(hide yes)
			(effects
				(font
					(size 1.27 1.27)
				)
			)
		)
		(property "Value" ""
			(at 0 0 0)
			(layer "F.Fab")
			(effects
				(font
					(size 1.27 1.27)
				)
			)
		)
		(duplicate_pad_numbers_are_jumpers no)
		(fp_poly
			(pts
				(xy 0.3048 -0.1016) (xy 0.3048 0.9906) (xy -0.3048 0.9906) (xy -0.3048 -0.1016)
			)
			(stroke
				(width 0)
				(type default)
			)
			(fill no)
			(layer "F.CrtYd")
		)
		(fp_line
			(start -0.3048 -0.1016)
			(end -0.3048 0.9906)
			(stroke
				(width 0.1)
				(type default)
			)
			(layer "F.Fab")
		)
		(fp_line
			(start -0.3048 0.9906)
			(end 0.3048 0.9906)
			(stroke
				(width 0.1)
				(type default)
			)
			(layer "F.Fab")
		)
		(fp_line
			(start 0.3048 -0.1016)
			(end -0.3048 -0.1016)
			(stroke
				(width 0.1)
				(type default)
			)
			(layer "F.Fab")
		)
		(fp_line
			(start 0.3048 0.9906)
			(end 0.3048 -0.1016)
			(stroke
				(width 0.1)
				(type default)
			)
			(layer "F.Fab")
		)
		(pad "1" smd rect
			(at 0 0)
			(size 0.508 0.508)
			(layers "F.Cu" "F.Mask" "F.Paste")
			(net "P3V3_DB1200_A")
		)
		(pad "2" smd rect
			(at 0 0.889)
			(size 0.508 0.508)
			(layers "F.Cu" "F.Mask" "F.Paste")
			(net "GND")
		)
		(zone
			(layer "F.Cu")
			(hatch none 0.5)
			(connect_pads
				(clearance 0)
			)
			(min_thickness 0.25)
			(keepout
				(tracks allowed)
				(vias not_allowed)
				(pads allowed)
				(copperpour not_allowed)
				(footprints allowed)
			)
			(placement
				(enabled no)
				(sheetname "")
			)
			(fill
				(thermal_gap 0.5)
				(thermal_bridge_width 0.5)
				(island_removal_mode 0)
			)
			(polygon
				(pts
					(xy 165.1 -74.549) (xy 165.608 -74.549) (xy 165.608 -74.168) (xy 165.1 -74.168)
				)
			)
		)
		(zone
			(layer "F.Cu")
			(hatch none 0.5)
			(connect_pads
				(clearance 0)
			)
			(min_thickness 0.25)
			(keepout
				(tracks not_allowed)
				(vias allowed)
				(pads allowed)
				(copperpour not_allowed)
				(footprints allowed)
			)
			(placement
				(enabled no)
				(sheetname "")
			)
			(fill
				(thermal_gap 0.5)
				(thermal_bridge_width 0.5)
				(island_removal_mode 0)
			)
			(polygon
				(pts
					(xy 165.1 -74.168) (xy 165.608 -74.168) (xy 165.608 -74.549) (xy 165.1 -74.549)
				)
			)
		)
	)
	(footprint ""
		(layer "F.Cu")
		(at 42.31513 -109.512862)
		(property "Reference" ""
			(at 0 0 0)
			(layer "F.SilkS")
			(hide yes)
			(effects
				(font
					(size 1.27 1.27)
				)
			)
		)
		(property "Value" ""
			(at 0 0 0)
			(layer "F.Fab")
			(effects
				(font
					(size 1.27 1.27)
				)
			)
		)
		(duplicate_pad_numbers_are_jumpers no)
		(fp_poly
			(pts
				(arc
					(start 2.032 0)
					(mid -2.032 0)
					(end 2.032 0)
				)
			)
			(stroke
				(width 0)
				(type default)
			)
			(fill no)
			(layer "F.CrtYd")
		)
		(pad "1" smd circle
			(at 0 0)
			(size 1.016 1.016)
			(layers "F.Cu" "F.Mask" "F.Paste")
			(net "Net_385")
		)
		(zone
			(layer "F.Cu")
			(hatch none 0.5)
			(connect_pads
				(clearance 0)
			)
			(min_thickness 0.25)
			(keepout
				(tracks not_allowed)
				(vias allowed)
				(pads allowed)
				(copperpour not_allowed)
				(footprints allowed)
			)
			(placement
				(enabled no)
				(sheetname "")
			)
			(fill
				(thermal_gap 0.5)
				(thermal_bridge_width 0.5)
				(island_removal_mode 0)
			)
			(polygon
				(pts
					(arc
						(start 43.83913 -109.512862)
						(mid 40.79113 -109.512862)
						(end 43.83913 -109.512862)
					)
				)
			)
		)
		(zone
			(layers "F.Cu" "B.Cu" "In1.Cu" "In2.Cu" "In3.Cu" "In4.Cu" "In5.Cu" "In6.Cu"
				"In7.Cu" "In8.Cu" "In9.Cu" "In10.Cu" "In11.Cu" "In12.Cu"
			)
			(hatch none 0.5)
			(connect_pads
				(clearance 0)
			)
			(min_thickness 0.25)
			(keepout
				(tracks allowed)
				(vias not_allowed)
				(pads allowed)
				(copperpour not_allowed)
				(footprints allowed)
			)
			(placement
				(enabled no)
				(sheetname "")
			)
			(fill
				(thermal_gap 0.5)
				(thermal_bridge_width 0.5)
				(island_removal_mode 0)
			)
			(polygon
				(pts
					(arc
						(start 43.83913 -109.512862)
						(mid 40.79113 -109.512862)
						(end 43.83913 -109.512862)
					)
				)
			)
		)
	)
	(footprint ""
		(layer "F.Cu")
		(at 186.015376 -59.243722 180)
		(property "Reference" "C22W13"
			(at 0 0 180)
			(layer "F.SilkS")
			(hide yes)
			(effects
				(font
					(size 1.27 1.27)
				)
			)
		)
		(property "Value" "*"
			(at -0.0762 -6.2357 180)
			(unlocked yes)
			(layer "F.Fab")
			(hide yes)
			(effects
				(font
					(size 1.27 1.016)
					(thickness 0.1524)
				)
			)
		)
		(property "Device Type" "SC22U16V5MX-4-GP_SMD-BCG5-SC22A"
			(at -0.0762 -8.2677 180)
			(unlocked yes)
			(layer "F.Fab")
			(hide yes)
			(effects
				(font
					(size 1.27 1.016)
					(thickness 0.1524)
				)
			)
		)
		(duplicate_pad_numbers_are_jumpers no)
		(fp_line
			(start 0.635 0)
			(end -0.635 0)
			(stroke
				(width 0.508)
				(type default)
			)
			(layer "F.SilkS")
		)
		(fp_rect
			(start -0.9652 1.778)
			(end 0.9652 -1.778)
			(stroke
				(width 0)
				(type default)
			)
			(fill no)
			(layer "F.CrtYd")
		)
		(fp_poly
			(pts
				(xy -0.9652 -1.778) (xy 0.9652 -1.778) (xy 0.9652 1.778) (xy -0.9652 1.778)
			)
			(stroke
				(width 0)
				(type default)
			)
			(fill no)
			(layer "F.Fab")
		)
		(pad "1" smd rect
			(at 0 -0.9652 180)
			(size 1.397 1.143)
			(layers "F.Cu" "F.Mask" "F.Paste")
			(net "VR_FET_SW_P12V_STBY_PVCCIN_CPU0")
		)
		(pad "2" smd rect
			(at 0 0.9652 180)
			(size 1.397 1.143)
			(layers "F.Cu" "F.Mask" "F.Paste")
			(net "GND")
		)
	)
	(footprint ""
		(layer "F.Cu")
		(at 324.5485 -121.666 -90)
		(property "Reference" "C828"
			(at -0.8382 -0.67818 270)
			(unlocked yes)
			(layer "F.SilkS")
			(effects
				(font
					(size 0.4064 0.254)
					(thickness 0.1524)
				)
				(justify left)
			)
		)
		(property "Value" ""
			(at 0 0 270)
			(layer "F.Fab")
			(effects
				(font
					(size 1.27 1.27)
				)
			)
		)
		(duplicate_pad_numbers_are_jumpers no)
		(fp_poly
			(pts
				(xy 0.3048 -0.1016) (xy 0.3048 0.9906) (xy -0.3048 0.9906) (xy -0.3048 -0.1016)
			)
			(stroke
				(width 0)
				(type default)
			)
			(fill no)
			(layer "F.CrtYd")
		)
		(fp_line
			(start -0.3048 0.9906)
			(end 0.3048 0.9906)
			(stroke
				(width 0.1)
				(type default)
			)
			(layer "F.Fab")
		)
		(fp_line
			(start 0.3048 0.9906)
			(end 0.3048 -0.1016)
			(stroke
				(width 0.1)
				(type default)
			)
			(layer "F.Fab")
		)
		(fp_line
			(start -0.3048 -0.1016)
			(end -0.3048 0.9906)
			(stroke
				(width 0.1)
				(type default)
			)
			(layer "F.Fab")
		)
		(fp_line
			(start 0.3048 -0.1016)
			(end -0.3048 -0.1016)
			(stroke
				(width 0.1)
				(type default)
			)
			(layer "F.Fab")
		)
		(pad "1" smd rect
			(at 0 0 270)
			(size 0.508 0.508)
			(layers "F.Cu" "F.Mask" "F.Paste")
			(net "P3E_CPU0_PE1_PCH_TXN<13>")
		)
		(pad "2" smd rect
			(at 0 0.889 270)
			(size 0.508 0.508)
			(layers "F.Cu" "F.Mask" "F.Paste")
			(net "P3E_CPU0_PE1_PCH_CON_TXN<13>")
		)
		(zone
			(layer "F.Cu")
			(hatch none 0.5)
			(connect_pads
				(clearance 0)
			)
			(min_thickness 0.25)
			(keepout
				(tracks allowed)
				(vias not_allowed)
				(pads allowed)
				(copperpour not_allowed)
				(footprints allowed)
			)
			(placement
				(enabled no)
				(sheetname "")
			)
			(fill
				(thermal_gap 0.5)
				(thermal_bridge_width 0.5)
				(island_removal_mode 0)
			)
			(polygon
				(pts
					(xy 324.2945 -121.92) (xy 324.2945 -121.412) (xy 323.9135 -121.412) (xy 323.9135 -121.92)
				)
			)
		)
	)
	(footprint ""
		(layer "F.Cu")
		(at 346.456 -104.267 180)
		(property "Reference" "C7C7"
			(at 0 0 180)
			(layer "F.SilkS")
			(hide yes)
			(effects
				(font
					(size 1.27 1.27)
				)
			)
		)
		(property "Value" "*"
			(at -0.0762 -6.2357 180)
			(unlocked yes)
			(layer "F.Fab")
			(hide yes)
			(effects
				(font
					(size 1.27 1.016)
					(thickness 0.1524)
				)
			)
		)
		(property "Device Type" "SC22U16V5MX-4-GP_SMD-BCG5-SC22A"
			(at -0.0762 -8.2677 180)
			(unlocked yes)
			(layer "F.Fab")
			(hide yes)
			(effects
				(font
					(size 1.27 1.016)
					(thickness 0.1524)
				)
			)
		)
		(duplicate_pad_numbers_are_jumpers no)
		(fp_line
			(start 0.635 0)
			(end -0.635 0)
			(stroke
				(width 0.508)
				(type default)
			)
			(layer "F.SilkS")
		)
		(fp_rect
			(start -0.9652 1.778)
			(end 0.9652 -1.778)
			(stroke
				(width 0)
				(type default)
			)
			(fill no)
			(layer "F.CrtYd")
		)
		(fp_poly
			(pts
				(xy -0.9652 -1.778) (xy 0.9652 -1.778) (xy 0.9652 1.778) (xy -0.9652 1.778)
			)
			(stroke
				(width 0)
				(type default)
			)
			(fill no)
			(layer "F.Fab")
		)
		(pad "1" smd rect
			(at 0 -0.9652 180)
			(size 1.397 1.143)
			(layers "F.Cu" "F.Mask" "F.Paste")
			(net "VR_FET_SW_P12V_STBY_PVCCIO_CPU0")
		)
		(pad "2" smd rect
			(at 0 0.9652 180)
			(size 1.397 1.143)
			(layers "F.Cu" "F.Mask" "F.Paste")
			(net "GND")
		)
	)
	(footprint ""
		(layer "F.Cu")
		(at 349.123 -17.78 180)
		(property "Reference" "C7F17"
			(at 0 0 180)
			(layer "F.SilkS")
			(hide yes)
			(effects
				(font
					(size 1.27 1.27)
				)
			)
		)
		(property "Value" ""
			(at 0 0 180)
			(layer "F.Fab")
			(effects
				(font
					(size 1.27 1.27)
				)
			)
		)
		(duplicate_pad_numbers_are_jumpers no)
		(fp_rect
			(start 0.3048 -0.1016)
			(end -0.3048 0.9906)
			(stroke
				(width 0)
				(type default)
			)
			(fill no)
			(layer "F.CrtYd")
		)
		(fp_line
			(start 0.3048 0.9906)
			(end 0.3048 -0.1016)
			(stroke
				(width 0.1)
				(type default)
			)
			(layer "F.Fab")
		)
		(fp_line
			(start 0.3048 -0.1016)
			(end -0.3048 -0.1016)
			(stroke
				(width 0.1)
				(type default)
			)
			(layer "F.Fab")
		)
		(fp_line
			(start -0.3048 0.9906)
			(end 0.3048 0.9906)
			(stroke
				(width 0.1)
				(type default)
			)
			(layer "F.Fab")
		)
		(fp_line
			(start -0.3048 -0.1016)
			(end -0.3048 0.9906)
			(stroke
				(width 0.1)
				(type default)
			)
			(layer "F.Fab")
		)
		(pad "1" smd rect
			(at 0 0 180)
			(size 0.508 0.508)
			(layers "F.Cu" "F.Mask" "F.Paste")
			(net "VR_PVDDQ_ABC_VDD")
		)
		(pad "2" smd rect
			(at 0 0.889 180)
			(size 0.508 0.508)
			(layers "F.Cu" "F.Mask" "F.Paste")
			(net "GND")
		)
		(zone
			(layer "F.Cu")
			(hatch none 0.5)
			(connect_pads
				(clearance 0)
			)
			(min_thickness 0.25)
			(keepout
				(tracks not_allowed)
				(vias allowed)
				(pads allowed)
				(copperpour not_allowed)
				(footprints allowed)
			)
			(placement
				(enabled no)
				(sheetname "")
			)
			(fill
				(thermal_gap 0.5)
				(thermal_bridge_width 0.5)
				(island_removal_mode 0)
			)
			(polygon
				(pts
					(xy 348.869 -18.034) (xy 349.377 -18.034) (xy 349.377 -18.415) (xy 348.869 -18.415)
				)
			)
		)
		(zone
			(layer "F.Cu")
			(hatch none 0.5)
			(connect_pads
				(clearance 0)
			)
			(min_thickness 0.25)
			(keepout
				(tracks allowed)
				(vias not_allowed)
				(pads allowed)
				(copperpour not_allowed)
				(footprints allowed)
			)
			(placement
				(enabled no)
				(sheetname "")
			)
			(fill
				(thermal_gap 0.5)
				(thermal_bridge_width 0.5)
				(island_removal_mode 0)
			)
			(polygon
				(pts
					(xy 348.869 -18.034) (xy 349.377 -18.034) (xy 349.377 -18.415) (xy 348.869 -18.415)
				)
			)
		)
	)
)
